# T6G (Grand Teton) — schematic netlist excerpt (pin names and nets, part order shuffled) for the footprints in the layout excerpt that follows; sources: Cadence DE-HDL packaged netlist, KiCad conversion of 04192023_DAF0TMB3IC0_F0TG_MB_C_brd_V02_OCP.brd

R1010  Q_RES  0 5% EMPTY  pkg 0603LF  page 290 : A = P0V9_CPU0_RT_2D ; B = P0V9_CPU0_RT1_2A_2D
PR6821  Q_RES  0 5% CHIP  pkg 0402LF  page 364 : A = P0V9_RETIMER_CPU1_VMON ; B = GND

(kicad_pcb
	(version 20260206)
	(generator "pcbnew")
	(generator_version "10.0")
	(general
		(thickness 1.6)
		(legacy_teardrops no)
	)
	(paper "A4")
	(title_block
		(title "04192023_DAF0TMB3IC0_F0TG_MB_C_brd_V02_OCP.brd")
		(comment 1 "Grand Teton / footprints 7684-7685 of 8354")
	)
	(layers
		(0 "F.Cu" signal "TOP")
		(4 "In1.Cu" signal "GND")
		(6 "In2.Cu" signal "IN1")
		(8 "In3.Cu" signal "GND1")
		(10 "In4.Cu" signal "IN2")
		(12 "In5.Cu" signal "GND2")
		(14 "In6.Cu" signal "IN3")
		(16 "In7.Cu" signal "GND3")
		(18 "In8.Cu" signal "VCC")
		(20 "In9.Cu" signal "VCC1")
		(22 "In10.Cu" signal "GND4")
		(24 "In11.Cu" signal "IN4")
		(26 "In12.Cu" signal "GND5")
		(28 "In13.Cu" signal "IN5")
		(30 "In14.Cu" signal "GND6")
		(32 "In15.Cu" signal "IN6")
		(34 "In16.Cu" signal "GND7")
		(2 "B.Cu" signal "BOTTOM")
		(9 "F.Adhes" user "F.Adhesive")
		(11 "B.Adhes" user "B.Adhesive")
		(13 "F.Paste" user "Package Geometry/Pastemask Top")
		(15 "B.Paste" user "Package Geometry/Pastemask Bottom")
		(5 "F.SilkS" user "Ref Des/Silkscreen Top")
		(7 "B.SilkS" user "Ref Des/Silkscreen Bottom")
		(1 "F.Mask" user "Board Geometry/Soldermask Top")
		(3 "B.Mask" user "Board Geometry/Soldermask Bottom")
		(17 "Dwgs.User" user "User.Drawings")
		(19 "Cmts.User" user "User.Comments")
		(21 "Eco1.User" user "User.Eco1")
		(23 "Eco2.User" user "User.Eco2")
		(25 "Edge.Cuts" user "Board Geometry/Outline")
		(27 "Margin" user)
		(31 "F.CrtYd" user "Package Geometry/Place Bound Top")
		(29 "B.CrtYd" user "Package Geometry/Place Bound Bottom")
		(35 "F.Fab" user "Ref Des/Assembly Top")
		(33 "B.Fab" user "Ref Des/Assembly Bottom")
	)
	(footprint ""
		(layer "B.Cu")
		(at 13.241782 -409.624784 180)
		(property "Reference" "PR6821"
			(at 0 0 0)
			(layer "B.SilkS")
			(hide yes)
			(effects
				(font
					(size 1.27 1.27)
				)
				(justify mirror)
			)
		)
		(property "Value" ""
			(at 0 0 0)
			(layer "B.Fab")
			(effects
				(font
					(size 1.27 1.27)
				)
				(justify mirror)
			)
		)
		(duplicate_pad_numbers_are_jumpers no)
		(fp_line
			(start 0.7874 0.4064)
			(end 0.7874 -0.4064)
			(stroke
				(width 0.1524)
				(type default)
			)
			(layer "B.SilkS")
		)
		(fp_line
			(start 0.7874 -0.4064)
			(end -0.7874 -0.4064)
			(stroke
				(width 0.1524)
				(type default)
			)
			(layer "B.SilkS")
		)
		(fp_line
			(start -0.7874 0.4064)
			(end 0.7874 0.4064)
			(stroke
				(width 0.1524)
				(type default)
			)
			(layer "B.SilkS")
		)
		(fp_line
			(start -0.7874 -0.4064)
			(end -0.7874 0.4064)
			(stroke
				(width 0.1524)
				(type default)
			)
			(layer "B.SilkS")
		)
		(fp_line
			(start 0.67945 0.3048)
			(end 0.67945 -0.305054)
			(stroke
				(width 0.1)
				(type default)
			)
			(layer "B.Fab")
		)
		(fp_line
			(start 0.67945 -0.305054)
			(end 0.12065 -0.305054)
			(stroke
				(width 0.1)
				(type default)
			)
			(layer "B.Fab")
		)
		(fp_line
			(start 0.12065 0.3048)
			(end 0.67945 0.3048)
			(stroke
				(width 0.1)
				(type default)
			)
			(layer "B.Fab")
		)
		(fp_line
			(start 0.12065 0.2794)
			(end 0.12065 0.3048)
			(stroke
				(width 0.1)
				(type default)
			)
			(layer "B.Fab")
		)
		(fp_line
			(start 0.12065 -0.2794)
			(end -0.12065 -0.2794)
			(stroke
				(width 0.1)
				(type default)
			)
			(layer "B.Fab")
		)
		(fp_line
			(start 0.12065 -0.305054)
			(end 0.12065 -0.2794)
			(stroke
				(width 0.1)
				(type default)
			)
			(layer "B.Fab")
		)
		(fp_line
			(start -0.120396 0.3048)
			(end -0.120396 0.2794)
			(stroke
				(width 0.1)
				(type default)
			)
			(layer "B.Fab")
		)
		(fp_line
			(start -0.120396 0.2794)
			(end 0.12065 0.2794)
			(stroke
				(width 0.1)
				(type default)
			)
			(layer "B.Fab")
		)
		(fp_line
			(start -0.12065 -0.2794)
			(end -0.12065 -0.3048)
			(stroke
				(width 0.1)
				(type default)
			)
			(layer "B.Fab")
		)
		(fp_line
			(start -0.12065 -0.3048)
			(end -0.67945 -0.3048)
			(stroke
				(width 0.1)
				(type default)
			)
			(layer "B.Fab")
		)
		(fp_line
			(start -0.67945 0.3048)
			(end -0.120396 0.3048)
			(stroke
				(width 0.1)
				(type default)
			)
			(layer "B.Fab")
		)
		(fp_line
			(start -0.67945 -0.3048)
			(end -0.67945 0.3048)
			(stroke
				(width 0.1)
				(type default)
			)
			(layer "B.Fab")
		)
		(pad "1" smd circle
			(at 0.40005 0)
			(size 0 0)
			(layers "B.Cu" "B.Mask" "B.Paste")
			(net "P0V9_RETIMER_CPU1_VMON")
		)
		(pad "2" smd circle
			(at -0.40005 0)
			(size 0 0)
			(layers "B.Cu" "B.Mask" "B.Paste")
			(net "GND")
		)
	)
	(footprint ""
		(layer "B.Cu")
		(at 328.416158 -401.624546 180)
		(property "Reference" "R1010"
			(at 0 0 0)
			(layer "B.SilkS")
			(hide yes)
			(effects
				(font
					(size 1.27 1.27)
				)
				(justify mirror)
			)
		)
		(property "Value" ""
			(at 0 0 0)
			(layer "B.Fab")
			(effects
				(font
					(size 1.27 1.27)
				)
				(justify mirror)
			)
		)
		(duplicate_pad_numbers_are_jumpers no)
		(fp_line
			(start 1.2954 0.5842)
			(end 1.2954 -0.5842)
			(stroke
				(width 0.1524)
				(type default)
			)
			(layer "B.SilkS")
		)
		(fp_line
			(start 1.2954 -0.5842)
			(end -1.2954 -0.5842)
			(stroke
				(width 0.1524)
				(type default)
			)
			(layer "B.SilkS")
		)
		(fp_line
			(start -1.2954 0.5842)
			(end 1.2954 0.5842)
			(stroke
				(width 0.1524)
				(type default)
			)
			(layer "B.SilkS")
		)
		(fp_line
			(start -1.2954 -0.5842)
			(end -1.2954 0.5842)
			(stroke
				(width 0.1524)
				(type default)
			)
			(layer "B.SilkS")
		)
		(fp_line
			(start 1.1938 0.4064)
			(end 1.1938 -0.406654)
			(stroke
				(width 0.1)
				(type default)
			)
			(layer "B.Fab")
		)
		(fp_line
			(start 1.1938 -0.406654)
			(end 0.8636 -0.406654)
			(stroke
				(width 0.1)
				(type default)
			)
			(layer "B.Fab")
		)
		(fp_line
			(start 0.8636 0.4572)
			(end 0.8636 0.4318)
			(stroke
				(width 0.1)
				(type default)
			)
			(layer "B.Fab")
		)
		(fp_line
			(start 0.8636 0.4318)
			(end 0.8636 0.4064)
			(stroke
				(width 0.1)
				(type default)
			)
			(layer "B.Fab")
		)
		(fp_line
			(start 0.8636 0.4064)
			(end 1.1938 0.4064)
			(stroke
				(width 0.1)
				(type default)
			)
			(layer "B.Fab")
		)
		(fp_line
			(start 0.8636 -0.406654)
			(end 0.8636 -0.4572)
			(stroke
				(width 0.1)
				(type default)
			)
			(layer "B.Fab")
		)
		(fp_line
			(start 0.8636 -0.4572)
			(end -0.8636 -0.4572)
			(stroke
				(width 0.1)
				(type default)
			)
			(layer "B.Fab")
		)
		(fp_line
			(start -0.8636 0.4572)
			(end 0.8636 0.4572)
			(stroke
				(width 0.1)
				(type default)
			)
			(layer "B.Fab")
		)
		(fp_line
			(start -0.8636 0.4064)
			(end -0.8636 0.4572)
			(stroke
				(width 0.1)
				(type default)
			)
			(layer "B.Fab")
		)
		(fp_line
			(start -0.8636 -0.406654)
			(end -1.1938 -0.406654)
			(stroke
				(width 0.1)
				(type default)
			)
			(layer "B.Fab")
		)
		(fp_line
			(start -0.8636 -0.4572)
			(end -0.8636 -0.406654)
			(stroke
				(width 0.1)
				(type default)
			)
			(layer "B.Fab")
		)
		(fp_line
			(start -1.1938 0.4064)
			(end -0.8636 0.4064)
			(stroke
				(width 0.1)
				(type default)
			)
			(layer "B.Fab")
		)
		(fp_line
			(start -1.1938 -0.406654)
			(end -1.1938 0.4064)
			(stroke
				(width 0.1)
				(type default)
			)
			(layer "B.Fab")
		)
		(pad "1" smd rect
			(at 0.7366 0 90)
			(size 0.7112 0.8128)
			(layers "B.Cu" "B.Mask" "B.Paste")
			(net "P0V9_CPU0_RT_2D")
		)
		(pad "2" smd rect
			(at -0.7366 0 90)
			(size 0.7112 0.8128)
			(layers "B.Cu" "B.Mask" "B.Paste")
			(net "P0V9_CPU0_RT1_2A_2D")
		)
	)
)
